FILE_TYPE = MACRO_DRAWING;
SET COLOR_WIRE YELLOW;
SET COLOR_PROP ORANGE;
SET COLOR_DOT WHITE;
SET COLOR_ARC YELLOW;
SET COLOR_BODY GREEN;
SET COLOR_NOTE PURPLE;
SET PROP_DISPLAY VALUE;
SET PAGE_NUMBER P17;
FORCEADD SOCKET4677_AZIF0045P001C01CS..5
(475 2925);
FORCEPROP 1 LAST PART_NUMBER DGA^7000023
J 0
(-575 4075);
DISPLAY 0.723404 (-575 4075);
PAINT GREEN (-575 4075);
DISPLAY INVISIBLE (-575 4075);
FORCEPROP 2 LAST PART_TYPE SMLF
J 0
(-575 4250);
DISPLAY 1.021277 (-575 4250);
FORCEPROP 1 LAST MATERIAL IO
J 0
(-575 4000);
DISPLAY 0.723404 (-575 4000);
PAINT GREEN (-575 4000);
FORCEPROP 2 LAST VALUE SOCKET4677_AZIF0045-P001C01CS
J 0
(-575 4200);
DISPLAY 1.021277 (-575 4200);
FORCEPROP 1 LAST $LOCATION U2
J 0
(-575 4150);
DISPLAY 0.723404 (-575 4150);
PAINT GREEN (-575 4150);
FORCEPROP 0 LASTPIN (-725 3000) $PN AC78
J 2
(-735 3010);
DISPLAY 0.680851 (-735 3010);
PAINT MONO (-735 3010);
FORCEPROP 0 LASTPIN (-725 2950) $PN AD77
J 2
(-735 2960);
DISPLAY 0.680851 (-735 2960);
PAINT MONO (-735 2960);
FORCEPROP 0 LASTPIN (1675 3550) $PN AV65
J 0
(1685 3560);
DISPLAY 0.680851 (1685 3560);
PAINT MONO (1685 3560);
FORCEPROP 0 LASTPIN (1675 2800) $PN AY24
J 0
(1685 2810);
DISPLAY 0.680851 (1685 2810);
PAINT MONO (1685 2810);
FORCEPROP 0 LASTPIN (1675 2600) $PN BA25
J 0
(1685 2610);
DISPLAY 0.680851 (1685 2610);
PAINT MONO (1685 2610);
FORCEPROP 0 LASTPIN (1675 3400) $PN BD71
J 0
(1685 3410);
DISPLAY 0.680851 (1685 3410);
PAINT MONO (1685 3410);
FORCEPROP 0 LASTPIN (1675 2050) $PN BE21
J 0
(1685 2060);
DISPLAY 0.680851 (1685 2060);
PAINT MONO (1685 2060);
FORCEPROP 0 LASTPIN (1675 3450) $PN BF71
J 0
(1685 3460);
DISPLAY 0.680851 (1685 3460);
PAINT MONO (1685 3460);
FORCEPROP 0 LASTPIN (-725 2850) $PN BG78
J 2
(-735 2860);
DISPLAY 0.680851 (-735 2860);
PAINT MONO (-735 2860);
FORCEPROP 0 LASTPIN (1675 3650) $PN BJ21
J 0
(1685 3660);
DISPLAY 0.680851 (1685 3660);
PAINT MONO (1685 3660);
FORCEPROP 0 LASTPIN (1675 3700) $PN BK22
J 0
(1685 3710);
DISPLAY 0.680851 (1685 3710);
PAINT MONO (1685 3710);
FORCEPROP 0 LASTPIN (-725 2800) $PN BL60
J 2
(-735 2810);
DISPLAY 0.680851 (-735 2810);
PAINT MONO (-735 2810);
FORCEPROP 0 LASTPIN (1675 2750) $PN BM65
J 0
(1685 2760);
DISPLAY 0.680851 (1685 2760);
PAINT MONO (1685 2760);
FORCEPROP 0 LASTPIN (1675 3800) $PN BP22
J 0
(1685 3810);
DISPLAY 0.680851 (1685 3810);
PAINT MONO (1685 3810);
FORCEPROP 0 LASTPIN (1675 2550) $PN BP65
J 0
(1685 2560);
DISPLAY 0.680851 (1685 2560);
PAINT MONO (1685 2560);
FORCEPROP 0 LASTPIN (1675 3750) $PN BR21
J 0
(1685 3760);
DISPLAY 0.680851 (1685 3760);
PAINT MONO (1685 3760);
FORCEPROP 0 LASTPIN (1675 3500) $PN CC66
J 0
(1685 3510);
DISPLAY 0.680851 (1685 3510);
PAINT MONO (1685 3510);
FORCEPROP 0 LASTPIN (1675 3150) $PN CD22
J 0
(1685 3160);
DISPLAY 0.680851 (1685 3160);
PAINT MONO (1685 3160);
FORCEPROP 0 LASTPIN (1675 3300) $PN CD26
J 0
(1685 3310);
DISPLAY 0.680851 (1685 3310);
PAINT MONO (1685 3310);
FORCEPROP 0 LASTPIN (1675 3250) $PN CD30
J 0
(1685 3260);
DISPLAY 0.680851 (1685 3260);
PAINT MONO (1685 3260);
FORCEPROP 0 LASTPIN (1675 3200) $PN CF22
J 0
(1685 3210);
DISPLAY 0.680851 (1685 3210);
PAINT MONO (1685 3210);
FORCEPROP 0 LASTPIN (1675 3000) $PN CH69
J 0
(1685 3010);
DISPLAY 0.680851 (1685 3010);
PAINT MONO (1685 3010);
FORCEPROP 0 LASTPIN (1675 2950) $PN CJ68
J 0
(1685 2960);
DISPLAY 0.680851 (1685 2960);
PAINT MONO (1685 2960);
FORCEPROP 0 LASTPIN (1675 3050) $PN CJ70
J 0
(1685 3060);
DISPLAY 0.680851 (1685 3060);
PAINT MONO (1685 3060);
FORCEPROP 0 LASTPIN (1675 2900) $PN CK67
J 0
(1685 2910);
DISPLAY 0.680851 (1685 2910);
PAINT MONO (1685 2910);
FORCEPROP 0 LASTPIN (1675 2500) $PN CR25
J 0
(1685 2510);
DISPLAY 0.680851 (1685 2510);
PAINT MONO (1685 2510);
FORCEPROP 0 LASTPIN (1675 2700) $PN CT26
J 0
(1685 2710);
DISPLAY 0.680851 (1685 2710);
PAINT MONO (1685 2710);
FORCEPROP 0 LASTPIN (-725 3100) $PN CW41
J 2
(-735 3110);
DISPLAY 0.680851 (-735 3110);
PAINT MONO (-735 3110);
FORCEPROP 0 LASTPIN (1675 2650) $PN CW58
J 0
(1685 2660);
DISPLAY 0.680851 (1685 2660);
PAINT MONO (1685 2660);
FORCEPROP 0 LASTPIN (1675 2450) $PN CY57
J 0
(1685 2460);
DISPLAY 0.680851 (1685 2460);
PAINT MONO (1685 2460);
FORCEPROP 0 LASTPIN (-725 3250) $PN EG17
J 2
(-735 3260);
DISPLAY 0.680851 (-735 3260);
PAINT MONO (-735 3260);
FORCEPROP 0 LASTPIN (-725 3300) $PN U17
J 2
(-735 3310);
DISPLAY 0.680851 (-735 3310);
PAINT MONO (-735 3310);
FORCEPROP 0 LASTPIN (-725 3150) $PN W17
J 2
(-735 3160);
DISPLAY 0.680851 (-735 3160);
PAINT MONO (-735 3160);
FORCEPROP 2 LAST CDS_LIB pure_quanta
J 0
(475 2925);
DISPLAY INVISIBLE (475 2925);
FORCEPROP 1 LAST NEEDS_NO_SIZE TRUE
J 0
(475 2925);
DISPLAY 0.723404 (475 2925);
PAINT GREEN (475 2925);
DISPLAY INVISIBLE (475 2925);
FORCEPROP 1 LAST CDS_LMAN_SYM_OUTLINE -1050,1050,1050,-1000
J 0
(475 2925);
DISPLAY 0.468085 (475 2925);
PAINT GREEN (475 2925);
DISPLAY INVISIBLE (475 2925);
FORCEPROP 2 LAST CDS_LOCATION U2
J 0
(-575 4300);
DISPLAY 1.021277 (-575 4300);
DISPLAY INVISIBLE (-575 4300);
FORCEPROP 0 LAST $SEC 5
J 0
(-575 4300);
DISPLAY 0.680851 (-575 4300);
PAINT MONO (-575 4300);
DISPLAY INVISIBLE (-575 4300);
FORCEPROP 2 LAST CDS_SEC 5
J 0
(-575 4300);
DISPLAY 1.021277 (-575 4300);
DISPLAY INVISIBLE (-575 4300);
FORCEPROP 1 LAST PATH I1
J 0
(475 2925);
DISPLAY 0.723404 (475 2925);
PAINT GREEN (475 2925);
DISPLAY INVISIBLE (475 2925);
FORCEADD QUANTA_TITLE_BLOCK_C..1
(5100 -1725);
FORCEPROP 0 LAST CDS_CON_LAST_MODIFIED Fri Aug 25 14:00:03 2023
J 0
(3215 -1710);
PAINT MONO (3215 -1710);
DISPLAY INVISIBLE (3215 -1710);
FORCEPROP 2 LAST CUSTOM_TXT_CDS <XR_PAGE_TITLE>
J 0
(-2790 3525);
DISPLAY 0.638298 (-2790 3525);
PAINT PINK (-2790 3525);
DISPLAY INVISIBLE (-2790 3525);
FORCEPROP 2 LAST CUSTOM_TXT_CDS <CON_LAST_MODIFIED>
J 0
(3215 -1710);
DISPLAY 0.978723 (3215 -1710);
FORCEPROP 2 LAST CUSTOM_TXT_CDS <Q_PROJ>
J 0
(2718 -1623);
DISPLAY 1.212766 (2718 -1623);
FORCEPROP 2 LAST CUSTOM_TXT_CDS <Q_NUMBER>
J 0
(3697 -1622);
DISPLAY 1.212766 (3697 -1622);
FORCEPROP 2 LAST CUSTOM_TXT_CDS <Q_REV>
J 0
(4916 -1622);
DISPLAY 1.212766 (4916 -1622);
FORCEPROP 2 LAST CUSTOM_TXT_CDS <CON_PAGE_NUM> OF <CON_TOTAL_PAGES>
J 0
(4654 -1707);
DISPLAY 0.978723 (4654 -1707);
FORCEPROP 1 LAST CUSTOM_TXT_CDS <NAME_2>
J 0
(1925 -1675);
FORCEPROP 1 LAST CUSTOM_TXT_CDS <NAME_1>
J 0
(1925 -1550);
FORCEPROP 1 LAST Q_TITLE SPR CPU0 MISC:VIEW MDFI/HBM(5 OF 30)
J 0
(-4266 -1699);
DISPLAY 1.957447 (-4266 -1699);
PAINT GREEN (-4266 -1699);
FORCEPROP 1 LAST Q_DEPT 
J 1
(1337 -1676);
DISPLAY 1.957447 (1337 -1676);
PAINT GREEN (1337 -1676);
FORCEPROP 2 LAST CDS_LIB pure_quanta
J 0
(5100 -1725);
PAINT MONO (5100 -1725);
DISPLAY INVISIBLE (5100 -1725);
FORCEPROP 1 LAST CDS_LMAN_SYM_OUTLINE -9475,6775,100,-125
J 0
(5100 -1725);
DISPLAY 0.468085 (5100 -1725);
PAINT GREEN (5100 -1725);
DISPLAY INVISIBLE (5100 -1725);
FORCEPROP 2 LAST PAGE_BORDER TRUE
J 0
(-2790 3525);
DISPLAY 0.638298 (-2790 3525);
PAINT PINK (-2790 3525);
DISPLAY INVISIBLE (-2790 3525);
FORCEPROP 2 LAST CDS_XR_PAGE_TITLE CR-17 : @S9S_MB_2U_LIB.S9S_MB_2U(SCH_1):PAGE17
J 0
(-2790 3525);
DISPLAY 0.638298 (-2790 3525);
PAINT PINK (-2790 3525);
DISPLAY INVISIBLE (-2790 3525);
FORCEPROP 1 LAST COMMENT_BODY TRUE
J 0
(5112 -1738);
DISPLAY 0.978723 (5112 -1738);
PAINT GREEN (5112 -1738);
DISPLAY INVISIBLE (5112 -1738);
WIRE 16 -1 (-725 3000)(-2400 3000);
FORCEPROP 2 LAST SIG_NAME NC_CPU0_HBM2_VIEWDIG0
J 0
(-2337 3009);
DISPLAY 0.680851 (-2337 3009);
PAINT WHITE (-2337 3009);
WIRE 16 -1 (-2400 2950)(-725 2950);
FORCEPROP 2 LAST SIG_NAME NC_CPU0_HBM2_VIEWDIG1
J 0
(-2337 2959);
DISPLAY 0.680851 (-2337 2959);
PAINT WHITE (-2337 2959);
WIRE 16 -1 (3350 2950)(1675 2950);
FORCEPROP 2 LAST SIG_NAME NC_CPU0_MDFI_DIE11_NS0
J 0
(1934 2959);
DISPLAY 0.680851 (1934 2959);
PAINT WHITE (1934 2959);
WIRE 16 -1 (3350 3050)(1675 3050);
FORCEPROP 2 LAST SIG_NAME NC_CPU0_MDFI_DIE11_EW0
J 0
(1934 3059);
DISPLAY 0.680851 (1934 3059);
PAINT WHITE (1934 3059);
WIRE 16 -1 (3350 2900)(1675 2900);
FORCEPROP 2 LAST SIG_NAME NC_CPU0_MDFI_DIE11_NS1
J 0
(1934 2909);
DISPLAY 0.680851 (1934 2909);
PAINT WHITE (1934 2909);
WIRE 16 -1 (3350 2500)(1675 2500);
FORCEPROP 2 LAST SIG_NAME NC_CPU0_VIEWPIN_GNR2
J 0
(1934 2509);
DISPLAY 0.680851 (1934 2509);
PAINT WHITE (1934 2509);
WIRE 16 -1 (3350 2700)(1675 2700);
FORCEPROP 2 LAST SIG_NAME NC_CPU0_VIEWPIN_GNR0
J 0
(1934 2709);
DISPLAY 0.680851 (1934 2709);
PAINT WHITE (1934 2709);
WIRE 16 -1 (-2400 3100)(-725 3100);
FORCEPROP 2 LAST SIG_NAME NC_CPU0_HBM1_VIEWDIG1
J 0
(-2337 3109);
DISPLAY 0.680851 (-2337 3109);
PAINT WHITE (-2337 3109);
WIRE 16 -1 (3350 2650)(1675 2650);
FORCEPROP 2 LAST SIG_NAME NC_CPU0_VIEWPIN_GNR1
J 0
(1934 2659);
DISPLAY 0.680851 (1934 2659);
PAINT WHITE (1934 2659);
WIRE 16 -1 (3350 2450)(1675 2450);
FORCEPROP 2 LAST SIG_NAME NC_CPU0_VIEWPIN_GNR3
J 0
(1934 2459);
DISPLAY 0.680851 (1934 2459);
PAINT WHITE (1934 2459);
WIRE 16 -1 (-2400 3250)(-725 3250);
FORCEPROP 2 LAST SIG_NAME NC_CPU0_HBM0_VIEWDIG1
J 0
(-2337 3259);
DISPLAY 0.680851 (-2337 3259);
PAINT WHITE (-2337 3259);
WIRE 16 -1 (-725 3300)(-2400 3300);
FORCEPROP 2 LAST SIG_NAME NC_CPU0_HBM0_VIEWDIG0
J 0
(-2337 3309);
DISPLAY 0.680851 (-2337 3309);
PAINT WHITE (-2337 3309);
WIRE 16 -1 (-725 3150)(-2400 3150);
FORCEPROP 2 LAST SIG_NAME NC_CPU0_HBM1_VIEWDIG0
J 0
(-2337 3159);
DISPLAY 0.680851 (-2337 3159);
PAINT WHITE (-2337 3159);
WIRE 16 -1 (3350 3550)(1675 3550);
FORCEPROP 2 LAST SIG_NAME NC_CPU0_MDFI_DIE01_EW0
J 0
(1934 3559);
DISPLAY 0.680851 (1934 3559);
PAINT WHITE (1934 3559);
WIRE 16 -1 (3350 2800)(1675 2800);
FORCEPROP 2 LAST SIG_NAME NC_CPU0_SOC_SPARE0
J 0
(1934 2809);
DISPLAY 0.680851 (1934 2809);
PAINT WHITE (1934 2809);
WIRE 16 -1 (3350 2600)(1675 2600);
FORCEPROP 2 LAST SIG_NAME NC_CPU0_SOC_SPARE4
J 0
(1934 2609);
DISPLAY 0.680851 (1934 2609);
PAINT WHITE (1934 2609);
WIRE 16 -1 (3350 3400)(1675 3400);
FORCEPROP 2 LAST SIG_NAME NC_CPU0_MDFI_DIE01_NS1
J 0
(1934 3409);
DISPLAY 0.680851 (1934 3409);
PAINT WHITE (1934 3409);
WIRE 16 -1 (3350 2050)(1675 2050);
FORCEPROP 2 LAST SIG_NAME TP_CPU0_DIE_HVM_EN_LVC1
J 0
(1934 2059);
DISPLAY 0.680851 (1934 2059);
PAINT WHITE (1934 2059);
WIRE 16 -1 (3350 3450)(1675 3450);
FORCEPROP 2 LAST SIG_NAME NC_CPU0_MDFI_DIE01_NS0
J 0
(1934 3459);
DISPLAY 0.680851 (1934 3459);
PAINT WHITE (1934 3459);
WIRE 16 -1 (-725 2850)(-2400 2850);
FORCEPROP 2 LAST SIG_NAME NC_CPU0_HBM3_VIEWDIG0
J 0
(-2337 2859);
DISPLAY 0.680851 (-2337 2859);
PAINT WHITE (-2337 2859);
WIRE 16 -1 (3350 3650)(1675 3650);
FORCEPROP 2 LAST SIG_NAME NC_CPU0_MDFI_DIE00_NS1
J 0
(1934 3659);
DISPLAY 0.680851 (1934 3659);
PAINT WHITE (1934 3659);
WIRE 16 -1 (3350 3700)(1675 3700);
FORCEPROP 2 LAST SIG_NAME NC_CPU0_MDFI_DIE00_NS0
J 0
(1934 3709);
DISPLAY 0.680851 (1934 3709);
PAINT WHITE (1934 3709);
WIRE 16 -1 (-2400 2800)(-725 2800);
FORCEPROP 2 LAST SIG_NAME NC_CPU0_HBM3_VIEWDIG1
J 0
(-2337 2809);
DISPLAY 0.680851 (-2337 2809);
PAINT WHITE (-2337 2809);
WIRE 16 -1 (3350 2750)(1675 2750);
FORCEPROP 2 LAST SIG_NAME NC_CPU0_SOC_SPARE1
J 0
(1934 2759);
DISPLAY 0.680851 (1934 2759);
PAINT WHITE (1934 2759);
WIRE 16 -1 (3350 3800)(1675 3800);
FORCEPROP 2 LAST SIG_NAME NC_CPU0_MDFI_DIE00_EW0
J 0
(1934 3809);
DISPLAY 0.680851 (1934 3809);
PAINT WHITE (1934 3809);
WIRE 16 -1 (3350 2550)(1675 2550);
FORCEPROP 2 LAST SIG_NAME NC_CPU0_SOC_SPARE5
J 0
(1934 2559);
DISPLAY 0.680851 (1934 2559);
PAINT WHITE (1934 2559);
WIRE 16 -1 (3350 3750)(1675 3750);
FORCEPROP 2 LAST SIG_NAME NC_CPU0_MDFI_DIE00_EW1
J 0
(1934 3759);
DISPLAY 0.680851 (1934 3759);
PAINT WHITE (1934 3759);
WIRE 16 -1 (3350 3500)(1675 3500);
FORCEPROP 2 LAST SIG_NAME NC_CPU0_MDFI_DIE01_EW1
J 0
(1934 3509);
DISPLAY 0.680851 (1934 3509);
PAINT WHITE (1934 3509);
WIRE 16 -1 (3350 3150)(1675 3150);
FORCEPROP 2 LAST SIG_NAME NC_CPU0_MDFI_DIE10_NS1
J 0
(1934 3159);
DISPLAY 0.680851 (1934 3159);
PAINT WHITE (1934 3159);
WIRE 16 -1 (3350 3300)(1675 3300);
FORCEPROP 2 LAST SIG_NAME NC_CPU0_MDFI_DIE10_EW0
J 0
(1934 3309);
DISPLAY 0.680851 (1934 3309);
PAINT WHITE (1934 3309);
WIRE 16 -1 (3350 3250)(1675 3250);
FORCEPROP 2 LAST SIG_NAME NC_CPU0_MDFI_DIE10_EW1
J 0
(1934 3259);
DISPLAY 0.680851 (1934 3259);
PAINT WHITE (1934 3259);
WIRE 16 -1 (3350 3200)(1675 3200);
FORCEPROP 2 LAST SIG_NAME NC_CPU0_MDFI_DIE10_NS0
J 0
(1934 3209);
DISPLAY 0.680851 (1934 3209);
PAINT WHITE (1934 3209);
WIRE 16 -1 (3350 3000)(1675 3000);
FORCEPROP 2 LAST SIG_NAME NC_CPU0_MDFI_DIE11_EW1
J 0
(1934 3009);
DISPLAY 0.680851 (1934 3009);
PAINT WHITE (1934 3009);
QUIT
